FILE_TYPE = MACRO_DRAWING;
SET COLOR_WIRE YELLOW;
SET COLOR_PROP ORANGE;
SET COLOR_DOT WHITE;
SET COLOR_ARC YELLOW;
SET COLOR_BODY GREEN;
SET COLOR_NOTE PURPLE;
SET PROP_DISPLAY VALUE;
SET PAGE_NUMBER P174;
FORCEADD OFFPAGE..1
(-7875 4050);
FORCEPROP 2 LAST $XR4 174 
J 0
(-8607 4050);
DISPLAY 0.638298 (-8607 4050);
PAINT MONO (-8607 4050);
FORCEPROP 2 LAST $XR3 172 
J 0
(-8487 4050);
DISPLAY 0.638298 (-8487 4050);
PAINT MONO (-8487 4050);
FORCEPROP 2 LAST $XR2 171 
J 0
(-8367 4050);
DISPLAY 0.638298 (-8367 4050);
PAINT MONO (-8367 4050);
FORCEPROP 2 LAST $XR1 170 
J 0
(-8247 4050);
DISPLAY 0.638298 (-8247 4050);
PAINT MONO (-8247 4050);
FORCEPROP 2 LAST $XR0 169 
J 0
(-8127 4050);
DISPLAY 0.638298 (-8127 4050);
PAINT MONO (-8127 4050);
FORCEPROP 2 LAST PATH I1
J 0
(-7825 4125);
DISPLAY 1.021277 (-7825 4125);
DISPLAY INVISIBLE (-7825 4125);
FORCEPROP 1 LAST COMMENT_BODY TRUE
J 0
(-7750 3950);
DISPLAY 0.872340 (-7750 3950);
PAINT GREEN (-7750 3950);
DISPLAY INVISIBLE (-7750 3950);
FORCEPROP 1 LAST OFFPAGE TRUE
J 0
(-7550 3925);
DISPLAY 0.872340 (-7550 3925);
PAINT GREEN (-7550 3925);
DISPLAY INVISIBLE (-7550 3925);
FORCEPROP 2 LAST CDS_LIB standard
J 0
(-7875 4050);
DISPLAY INVISIBLE (-7875 4050);
FORCEADD UNIVERSAL_GND..1
(-5250 3425);
FORCEPROP 3 LASTPIN (-5250 3475) SIG_NAME GND\g
J 0
(-5240 3485);
DISPLAY 0.659574 (-5240 3485);
PAINT MONO (-5240 3485);
DISPLAY INVISIBLE (-5240 3485);
FORCEPROP 2 LAST CDS_LIB pure_quanta_power
J 0
(-5250 3425);
DISPLAY INVISIBLE (-5250 3425);
FORCEPROP 1 LAST PATH I16
J 0
(-5175 3425);
DISPLAY 0.872340 (-5175 3425);
PAINT AQUA (-5175 3425);
DISPLAY INVISIBLE (-5175 3425);
FORCEPROP 1 LAST HDL_POWER GND
J 1
(-5225 3350);
DISPLAY 0.872340 (-5225 3350);
PAINT GREEN (-5225 3350);
DISPLAY INVISIBLE (-5225 3350);
FORCEADD Q_RES..1
(-4050 3200);
FORCEPROP 1 LAST LOCATION PR367
J 0
(-4075 3250);
DISPLAY 0.489362 (-4075 3250);
PAINT SKYBLUE (-4075 3250);
FORCEPROP 0 LAST $SEC 1
J 0
(-4050 3275);
DISPLAY 0.680851 (-4050 3275);
PAINT MONO (-4050 3275);
DISPLAY INVISIBLE (-4050 3275);
FORCEPROP 0 LAST CDS_SEC 1
J 0
(-4050 3275);
DISPLAY 1.021277 (-4050 3275);
DISPLAY INVISIBLE (-4050 3275);
FORCEPROP 1 LASTPIN (-4150 3200) $PN 1
J 0
(-4138 3212);
DISPLAY 0.489362 (-4138 3212);
PAINT MONO (-4138 3212);
FORCEPROP 1 LASTPIN (-3950 3200) $PN 2
J 0
(-3988 3212);
DISPLAY 0.489362 (-3988 3212);
PAINT MONO (-3988 3212);
FORCEPROP 1 LAST WATTAGE 1/16W
J 0
(-3950 3150);
DISPLAY 0.489362 (-3950 3150);
PAINT SKYBLUE (-3950 3150);
FORCEPROP 1 LAST MATERIAL CHIP
J 0
(-4300 3100);
DISPLAY 0.489362 (-4300 3100);
PAINT SKYBLUE (-4300 3100);
FORCEPROP 1 LAST TOLERANCE 5%
J 0
(-3925 3225);
DISPLAY 0.489362 (-3925 3225);
PAINT SKYBLUE (-3925 3225);
FORCEPROP 1 LAST VALUE 0
J 2
(-4175 3225);
DISPLAY 0.489362 (-4175 3225);
PAINT SKYBLUE (-4175 3225);
FORCEPROP 1 LAST PART_NUMBER CS00002JB38
J 0
(-4300 3150);
DISPLAY 0.489362 (-4300 3150);
PAINT SKYBLUE (-4300 3150);
FORCEPROP 1 LAST PACK_TYPE 0402LF
J 0
(-3950 3100);
DISPLAY 0.489362 (-3950 3100);
PAINT SKYBLUE (-3950 3100);
FORCEPROP 2 LAST CDS_LIB pure_quanta
J 0
(-4050 3200);
DISPLAY INVISIBLE (-4050 3200);
FORCEPROP 1 LAST PATH I17
J 0
(-4100 3350);
DISPLAY 0.978723 (-4100 3350);
PAINT WHITE (-4100 3350);
DISPLAY INVISIBLE (-4100 3350);
FORCEADD Q_RES..1
(-4525 4500);
FORCEPROP 1 LAST LOCATION PR366
J 0
(-4550 4550);
DISPLAY 0.489362 (-4550 4550);
PAINT SKYBLUE (-4550 4550);
FORCEPROP 0 LAST $SEC 1
J 0
(-4500 4575);
DISPLAY 0.680851 (-4500 4575);
PAINT MONO (-4500 4575);
DISPLAY INVISIBLE (-4500 4575);
FORCEPROP 0 LAST CDS_SEC 1
J 0
(-4500 4575);
DISPLAY 1.021277 (-4500 4575);
DISPLAY INVISIBLE (-4500 4575);
FORCEPROP 1 LASTPIN (-4625 4500) $PN 1
J 0
(-4613 4512);
DISPLAY 0.489362 (-4613 4512);
PAINT MONO (-4613 4512);
FORCEPROP 1 LASTPIN (-4425 4500) $PN 2
J 0
(-4463 4512);
DISPLAY 0.489362 (-4463 4512);
PAINT MONO (-4463 4512);
FORCEPROP 1 LAST PACK_TYPE 0402LF
J 0
(-4425 4400);
DISPLAY 0.489362 (-4425 4400);
PAINT SKYBLUE (-4425 4400);
FORCEPROP 1 LAST TOLERANCE 1%
J 0
(-4400 4525);
DISPLAY 0.489362 (-4400 4525);
PAINT SKYBLUE (-4400 4525);
FORCEPROP 1 LAST MATERIAL CHIP
J 0
(-4775 4400);
DISPLAY 0.489362 (-4775 4400);
PAINT SKYBLUE (-4775 4400);
FORCEPROP 1 LAST WATTAGE 1/16W
J 0
(-4425 4450);
DISPLAY 0.489362 (-4425 4450);
PAINT SKYBLUE (-4425 4450);
FORCEPROP 1 LAST VALUE 4.7
J 2
(-4650 4525);
DISPLAY 0.489362 (-4650 4525);
PAINT SKYBLUE (-4650 4525);
FORCEPROP 1 LAST PART_NUMBER CS-4702FB19
J 0
(-4775 4450);
DISPLAY 0.489362 (-4775 4450);
PAINT SKYBLUE (-4775 4450);
FORCEPROP 1 LAST PATH I18
J 0
(-4575 4650);
DISPLAY 0.978723 (-4575 4650);
PAINT WHITE (-4575 4650);
DISPLAY INVISIBLE (-4575 4650);
FORCEPROP 2 LAST CDS_LIB pure_quanta
J 0
(-4525 4500);
DISPLAY INVISIBLE (-4525 4500);
FORCEADD UNIVERSAL_GND..1
(-7650 3600);
FORCEPROP 3 LASTPIN (-7650 3650) SIG_NAME GND\g
J 0
(-7640 3660);
DISPLAY 0.659574 (-7640 3660);
PAINT MONO (-7640 3660);
DISPLAY INVISIBLE (-7640 3660);
FORCEPROP 2 LAST CDS_LIB pure_quanta_power
J 0
(-7650 3600);
DISPLAY INVISIBLE (-7650 3600);
FORCEPROP 1 LAST PATH I2
J 0
(-7575 3600);
DISPLAY 0.872340 (-7575 3600);
PAINT AQUA (-7575 3600);
DISPLAY INVISIBLE (-7575 3600);
FORCEPROP 1 LAST HDL_POWER GND
J 1
(-7625 3525);
DISPLAY 0.872340 (-7625 3525);
PAINT GREEN (-7625 3525);
DISPLAY INVISIBLE (-7625 3525);
FORCEADD Q_CAP..1
(-4625 5025);
FORCEPROP 1 LAST LOCATION PC609_3
J 0
(-4575 5125);
DISPLAY 0.489362 (-4575 5125);
PAINT SKYBLUE (-4575 5125);
FORCEPROP 0 LAST $SEC 1
J 0
(-4575 5150);
DISPLAY 0.680851 (-4575 5150);
PAINT MONO (-4575 5150);
DISPLAY INVISIBLE (-4575 5150);
FORCEPROP 0 LAST CDS_SEC 1
J 0
(-4575 5150);
DISPLAY 1.021277 (-4575 5150);
DISPLAY INVISIBLE (-4575 5150);
FORCEPROP 1 LASTPIN (-4625 5125) $PN 1
J 0
(-4615 5105);
DISPLAY 0.489362 (-4615 5105);
PAINT MONO (-4615 5105);
FORCEPROP 1 LASTPIN (-4625 4925) $PN 2
J 0
(-4615 4905);
DISPLAY 0.489362 (-4615 4905);
PAINT MONO (-4615 4905);
FORCEPROP 1 LAST MATERIAL X6S
J 0
(-4575 4925);
DISPLAY 0.489362 (-4575 4925);
PAINT SKYBLUE (-4575 4925);
FORCEPROP 1 LAST TOLERANCE 10%
J 0
(-4575 4975);
DISPLAY 0.489362 (-4575 4975);
PAINT SKYBLUE (-4575 4975);
FORCEPROP 1 LAST VALUE 1UF
J 0
(-4575 5075);
DISPLAY 0.489362 (-4575 5075);
PAINT SKYBLUE (-4575 5075);
FORCEPROP 1 LAST PART_NUMBER CH5104KEB02
J 0
(-4575 4875);
DISPLAY 0.489362 (-4575 4875);
PAINT SKYBLUE (-4575 4875);
FORCEPROP 1 LAST VOLTAGE 25V
J 0
(-4575 5025);
DISPLAY 0.489362 (-4575 5025);
PAINT SKYBLUE (-4575 5025);
FORCEPROP 1 LAST PACK_TYPE C0402
J 0
(-4575 4825);
DISPLAY 0.489362 (-4575 4825);
PAINT SKYBLUE (-4575 4825);
FORCEPROP 2 LAST CDS_LIB pure_quanta
J 0
(-4625 5025);
DISPLAY INVISIBLE (-4625 5025);
FORCEPROP 1 LAST PATH I20
J 0
(-4575 5175);
DISPLAY 0.978723 (-4575 5175);
PAINT WHITE (-4575 5175);
DISPLAY INVISIBLE (-4575 5175);
FORCEADD Q_CAP..1
(-4300 5025);
FORCEPROP 1 LAST LOCATION PC610_3
J 0
(-4250 5125);
DISPLAY 0.489362 (-4250 5125);
PAINT SKYBLUE (-4250 5125);
FORCEPROP 0 LAST $SEC 1
J 0
(-4250 5150);
DISPLAY 0.680851 (-4250 5150);
PAINT MONO (-4250 5150);
DISPLAY INVISIBLE (-4250 5150);
FORCEPROP 0 LAST CDS_SEC 1
J 0
(-4250 5150);
DISPLAY 1.021277 (-4250 5150);
DISPLAY INVISIBLE (-4250 5150);
FORCEPROP 1 LASTPIN (-4300 5125) $PN 1
J 0
(-4290 5105);
DISPLAY 0.489362 (-4290 5105);
PAINT MONO (-4290 5105);
FORCEPROP 1 LASTPIN (-4300 4925) $PN 2
J 0
(-4290 4905);
DISPLAY 0.489362 (-4290 4905);
PAINT MONO (-4290 4905);
FORCEPROP 1 LAST MATERIAL X6S
J 0
(-4250 4925);
DISPLAY 0.489362 (-4250 4925);
PAINT SKYBLUE (-4250 4925);
FORCEPROP 1 LAST TOLERANCE 10%
J 0
(-4250 4975);
DISPLAY 0.489362 (-4250 4975);
PAINT SKYBLUE (-4250 4975);
FORCEPROP 1 LAST VALUE 10UF
J 0
(-4250 5075);
DISPLAY 0.489362 (-4250 5075);
PAINT SKYBLUE (-4250 5075);
FORCEPROP 1 LAST PART_NUMBER CH6104KEA00
J 0
(-4250 4875);
DISPLAY 0.489362 (-4250 4875);
PAINT SKYBLUE (-4250 4875);
FORCEPROP 1 LAST VOLTAGE 25V
J 0
(-4250 5025);
DISPLAY 0.489362 (-4250 5025);
PAINT SKYBLUE (-4250 5025);
FORCEPROP 1 LAST PACK_TYPE C0805
J 0
(-4250 4825);
DISPLAY 0.489362 (-4250 4825);
PAINT SKYBLUE (-4250 4825);
FORCEPROP 2 LAST CDS_LIB pure_quanta
J 0
(-4300 5025);
DISPLAY INVISIBLE (-4300 5025);
FORCEPROP 1 LAST PATH I21
J 0
(-4250 5175);
DISPLAY 0.978723 (-4250 5175);
PAINT WHITE (-4250 5175);
DISPLAY INVISIBLE (-4250 5175);
FORCEADD Q_CAP..1
(-3975 5025);
FORCEPROP 1 LAST LOCATION PC611_3
J 0
(-3925 5125);
DISPLAY 0.489362 (-3925 5125);
PAINT SKYBLUE (-3925 5125);
FORCEPROP 0 LAST $SEC 1
J 0
(-3925 5150);
DISPLAY 0.680851 (-3925 5150);
PAINT MONO (-3925 5150);
DISPLAY INVISIBLE (-3925 5150);
FORCEPROP 0 LAST CDS_SEC 1
J 0
(-3925 5150);
DISPLAY 1.021277 (-3925 5150);
DISPLAY INVISIBLE (-3925 5150);
FORCEPROP 1 LASTPIN (-3975 5125) $PN 1
J 0
(-3965 5105);
DISPLAY 0.489362 (-3965 5105);
PAINT MONO (-3965 5105);
FORCEPROP 1 LASTPIN (-3975 4925) $PN 2
J 0
(-3965 4905);
DISPLAY 0.489362 (-3965 4905);
PAINT MONO (-3965 4905);
FORCEPROP 1 LAST MATERIAL X6S
J 0
(-3925 4925);
DISPLAY 0.489362 (-3925 4925);
PAINT SKYBLUE (-3925 4925);
FORCEPROP 1 LAST TOLERANCE 10%
J 0
(-3925 4975);
DISPLAY 0.489362 (-3925 4975);
PAINT SKYBLUE (-3925 4975);
FORCEPROP 1 LAST VALUE 10UF
J 0
(-3925 5075);
DISPLAY 0.489362 (-3925 5075);
PAINT SKYBLUE (-3925 5075);
FORCEPROP 1 LAST PART_NUMBER CH6104KEA00
J 0
(-3925 4875);
DISPLAY 0.489362 (-3925 4875);
PAINT SKYBLUE (-3925 4875);
FORCEPROP 1 LAST VOLTAGE 25V
J 0
(-3925 5025);
DISPLAY 0.489362 (-3925 5025);
PAINT SKYBLUE (-3925 5025);
FORCEPROP 1 LAST PACK_TYPE C0805
J 0
(-3925 4825);
DISPLAY 0.489362 (-3925 4825);
PAINT SKYBLUE (-3925 4825);
FORCEPROP 2 LAST CDS_LIB pure_quanta
J 0
(-3975 5025);
DISPLAY INVISIBLE (-3975 5025);
FORCEPROP 1 LAST PATH I22
J 0
(-3925 5175);
DISPLAY 0.978723 (-3925 5175);
PAINT WHITE (-3925 5175);
DISPLAY INVISIBLE (-3925 5175);
FORCEADD UNIVERSAL_GND..1
(-3325 4700);
FORCEPROP 3 LASTPIN (-3325 4750) SIG_NAME GND\g
J 0
(-3315 4760);
DISPLAY 0.659574 (-3315 4760);
PAINT MONO (-3315 4760);
DISPLAY INVISIBLE (-3315 4760);
FORCEPROP 2 LAST CDS_LIB pure_quanta_power
J 0
(-3325 4700);
DISPLAY INVISIBLE (-3325 4700);
FORCEPROP 1 LAST PATH I23
J 0
(-3250 4700);
DISPLAY 0.872340 (-3250 4700);
PAINT AQUA (-3250 4700);
DISPLAY INVISIBLE (-3250 4700);
FORCEPROP 1 LAST HDL_POWER GND
J 1
(-3300 4625);
DISPLAY 0.872340 (-3300 4625);
PAINT GREEN (-3300 4625);
DISPLAY INVISIBLE (-3300 4625);
FORCEADD Q_CAP..1
(-1750 3975);
FORCEPROP 1 LAST LOCATION PC614_3
J 0
(-1700 4075);
DISPLAY 0.489362 (-1700 4075);
PAINT SKYBLUE (-1700 4075);
FORCEPROP 0 LAST $SEC 1
J 0
(-1700 4100);
DISPLAY 0.680851 (-1700 4100);
PAINT MONO (-1700 4100);
DISPLAY INVISIBLE (-1700 4100);
FORCEPROP 0 LAST CDS_SEC 1
J 0
(-1700 4100);
DISPLAY 1.021277 (-1700 4100);
DISPLAY INVISIBLE (-1700 4100);
FORCEPROP 1 LASTPIN (-1750 4075) $PN 1
J 0
(-1740 4055);
DISPLAY 0.489362 (-1740 4055);
PAINT MONO (-1740 4055);
FORCEPROP 1 LASTPIN (-1750 3875) $PN 2
J 0
(-1740 3855);
DISPLAY 0.489362 (-1740 3855);
PAINT MONO (-1740 3855);
FORCEPROP 1 LAST MATERIAL X6S
J 0
(-1700 3875);
DISPLAY 0.489362 (-1700 3875);
PAINT SKYBLUE (-1700 3875);
FORCEPROP 1 LAST TOLERANCE 20%
J 0
(-1700 3925);
DISPLAY 0.489362 (-1700 3925);
PAINT SKYBLUE (-1700 3925);
FORCEPROP 1 LAST VALUE 22UF
J 0
(-1700 4025);
DISPLAY 0.489362 (-1700 4025);
PAINT SKYBLUE (-1700 4025);
FORCEPROP 1 LAST PART_NUMBER TMP_QCH622KMEA01
J 0
(-1700 3825);
DISPLAY 0.489362 (-1700 3825);
PAINT SKYBLUE (-1700 3825);
FORCEPROP 1 LAST VOLTAGE 4V
J 0
(-1700 3975);
DISPLAY 0.489362 (-1700 3975);
PAINT SKYBLUE (-1700 3975);
FORCEPROP 1 LAST PACK_TYPE 0805
J 0
(-1700 3775);
DISPLAY 0.489362 (-1700 3775);
PAINT SKYBLUE (-1700 3775);
FORCEPROP 2 LAST CDS_LIB pure_quanta
J 0
(-1750 3975);
DISPLAY INVISIBLE (-1750 3975);
FORCEPROP 1 LAST PATH I25
J 0
(-1700 4125);
DISPLAY 0.978723 (-1700 4125);
PAINT WHITE (-1700 4125);
DISPLAY INVISIBLE (-1700 4125);
FORCEADD Q_CAP..1
(-3675 5025);
FORCEPROP 1 LAST LOCATION PC613_3
J 0
(-3625 5125);
DISPLAY 0.489362 (-3625 5125);
PAINT SKYBLUE (-3625 5125);
FORCEPROP 0 LAST $SEC 1
J 0
(-3625 5150);
DISPLAY 0.680851 (-3625 5150);
PAINT MONO (-3625 5150);
DISPLAY INVISIBLE (-3625 5150);
FORCEPROP 0 LAST CDS_SEC 1
J 0
(-3625 5150);
DISPLAY 1.021277 (-3625 5150);
DISPLAY INVISIBLE (-3625 5150);
FORCEPROP 1 LASTPIN (-3675 5125) $PN 1
J 0
(-3665 5105);
DISPLAY 0.489362 (-3665 5105);
PAINT MONO (-3665 5105);
FORCEPROP 1 LASTPIN (-3675 4925) $PN 2
J 0
(-3665 4905);
DISPLAY 0.489362 (-3665 4905);
PAINT MONO (-3665 4905);
FORCEPROP 1 LAST MATERIAL X6S
J 0
(-3625 4925);
DISPLAY 0.489362 (-3625 4925);
PAINT SKYBLUE (-3625 4925);
FORCEPROP 1 LAST TOLERANCE 10%
J 0
(-3625 4975);
DISPLAY 0.489362 (-3625 4975);
PAINT SKYBLUE (-3625 4975);
FORCEPROP 1 LAST VALUE 10UF
J 0
(-3625 5075);
DISPLAY 0.489362 (-3625 5075);
PAINT SKYBLUE (-3625 5075);
FORCEPROP 1 LAST PART_NUMBER CH6104KEA00
J 0
(-3625 4875);
DISPLAY 0.489362 (-3625 4875);
PAINT SKYBLUE (-3625 4875);
FORCEPROP 1 LAST VOLTAGE 25V
J 0
(-3625 5025);
DISPLAY 0.489362 (-3625 5025);
PAINT SKYBLUE (-3625 5025);
FORCEPROP 1 LAST PACK_TYPE C0805
J 0
(-3625 4825);
DISPLAY 0.489362 (-3625 4825);
PAINT SKYBLUE (-3625 4825);
FORCEPROP 2 LAST CDS_LIB pure_quanta
J 0
(-3675 5025);
DISPLAY INVISIBLE (-3675 5025);
FORCEPROP 1 LAST PATH I26
J 0
(-3625 5175);
DISPLAY 0.978723 (-3625 5175);
PAINT WHITE (-3625 5175);
DISPLAY INVISIBLE (-3625 5175);
FORCEADD VCC_CORE..1
(-3325 5325);
FORCEPROP 3 LASTPIN (-3325 5275) SIG_NAME SW_P12V_STBY_PVDDCR_SOC_P0_FLT\g
J 0
(-3315 5285);
DISPLAY 0.659574 (-3315 5285);
PAINT MONO (-3315 5285);
DISPLAY INVISIBLE (-3315 5285);
FORCEPROP 1 LAST HDL_POWER SW_P12V_STBY_PVDDCR_SOC_P0_FLT
J 1
(-3325 5375);
DISPLAY 0.489362 (-3325 5375);
PAINT GREEN (-3325 5375);
FORCEPROP 2 LAST CDS_LIB pure_quanta_power
J 0
(-3325 5325);
DISPLAY INVISIBLE (-3325 5325);
FORCEPROP 1 LAST PATH I27
J 0
(-3275 5350);
DISPLAY 0.872340 (-3275 5350);
PAINT AQUA (-3275 5350);
DISPLAY INVISIBLE (-3275 5350);
FORCEADD UNIVERSAL_GND..1
(-1325 3625);
FORCEPROP 3 LASTPIN (-1325 3675) SIG_NAME GND\g
J 0
(-1315 3685);
DISPLAY 0.659574 (-1315 3685);
PAINT MONO (-1315 3685);
DISPLAY INVISIBLE (-1315 3685);
FORCEPROP 2 LAST CDS_LIB pure_quanta_power
J 0
(-1325 3625);
DISPLAY INVISIBLE (-1325 3625);
FORCEPROP 1 LAST PATH I28
J 0
(-1250 3625);
DISPLAY 0.872340 (-1250 3625);
PAINT AQUA (-1250 3625);
DISPLAY INVISIBLE (-1250 3625);
FORCEPROP 1 LAST HDL_POWER GND
J 1
(-1300 3550);
DISPLAY 0.872340 (-1300 3550);
PAINT GREEN (-1300 3550);
DISPLAY INVISIBLE (-1300 3550);
FORCEADD Q_CAP..1
(-1325 3975);
FORCEPROP 1 LAST LOCATION PC615_3
J 0
(-1275 4075);
DISPLAY 0.489362 (-1275 4075);
PAINT SKYBLUE (-1275 4075);
FORCEPROP 0 LAST $SEC 1
J 0
(-1275 4100);
DISPLAY 0.680851 (-1275 4100);
PAINT MONO (-1275 4100);
DISPLAY INVISIBLE (-1275 4100);
FORCEPROP 0 LAST CDS_SEC 1
J 0
(-1275 4100);
DISPLAY 1.021277 (-1275 4100);
DISPLAY INVISIBLE (-1275 4100);
FORCEPROP 1 LASTPIN (-1325 4075) $PN 1
J 0
(-1315 4055);
DISPLAY 0.489362 (-1315 4055);
PAINT MONO (-1315 4055);
FORCEPROP 1 LASTPIN (-1325 3875) $PN 2
J 0
(-1315 3855);
DISPLAY 0.489362 (-1315 3855);
PAINT MONO (-1315 3855);
FORCEPROP 1 LAST MATERIAL X6S
J 0
(-1275 3875);
DISPLAY 0.489362 (-1275 3875);
PAINT SKYBLUE (-1275 3875);
FORCEPROP 1 LAST TOLERANCE 20%
J 0
(-1275 3925);
DISPLAY 0.489362 (-1275 3925);
PAINT SKYBLUE (-1275 3925);
FORCEPROP 1 LAST VALUE 22UF
J 0
(-1275 4025);
DISPLAY 0.489362 (-1275 4025);
PAINT SKYBLUE (-1275 4025);
FORCEPROP 1 LAST PART_NUMBER TMP_QCH622KMEA01
J 0
(-1275 3825);
DISPLAY 0.489362 (-1275 3825);
PAINT SKYBLUE (-1275 3825);
FORCEPROP 1 LAST VOLTAGE 4V
J 0
(-1275 3975);
DISPLAY 0.489362 (-1275 3975);
PAINT SKYBLUE (-1275 3975);
FORCEPROP 1 LAST PACK_TYPE 0805
J 0
(-1275 3775);
DISPLAY 0.489362 (-1275 3775);
PAINT SKYBLUE (-1275 3775);
FORCEPROP 2 LAST CDS_LIB pure_quanta
J 0
(-1325 3975);
DISPLAY INVISIBLE (-1325 3975);
FORCEPROP 1 LAST PATH I29
J 0
(-1275 4125);
DISPLAY 0.978723 (-1275 4125);
PAINT WHITE (-1275 4125);
DISPLAY INVISIBLE (-1275 4125);
FORCEADD UNIVERSAL_GND..1
(-7325 3675);
FORCEPROP 3 LASTPIN (-7325 3725) SIG_NAME GND\g
J 0
(-7315 3735);
DISPLAY 0.659574 (-7315 3735);
PAINT MONO (-7315 3735);
DISPLAY INVISIBLE (-7315 3735);
FORCEPROP 2 LAST CDS_LIB pure_quanta_power
J 0
(-7325 3675);
DISPLAY INVISIBLE (-7325 3675);
FORCEPROP 1 LAST PATH I3
J 0
(-7250 3675);
DISPLAY 0.872340 (-7250 3675);
PAINT AQUA (-7250 3675);
DISPLAY INVISIBLE (-7250 3675);
FORCEPROP 1 LAST HDL_POWER GND
J 1
(-7300 3600);
DISPLAY 0.872340 (-7300 3600);
PAINT GREEN (-7300 3600);
DISPLAY INVISIBLE (-7300 3600);
FORCEADD VCC_CORE..1
(-1325 4300);
FORCEPROP 3 LASTPIN (-1325 4250) SIG_NAME PVDDCR_SOC_P0\g
J 0
(-1315 4260);
DISPLAY 0.659574 (-1315 4260);
PAINT MONO (-1315 4260);
DISPLAY INVISIBLE (-1315 4260);
FORCEPROP 1 LAST HDL_POWER PVDDCR_SOC_P0
J 1
(-1325 4350);
DISPLAY 0.489362 (-1325 4350);
PAINT GREEN (-1325 4350);
FORCEPROP 2 LAST CDS_LIB pure_quanta_power
J 0
(-1325 4300);
DISPLAY INVISIBLE (-1325 4300);
FORCEPROP 1 LAST PATH I30
J 0
(-1275 4325);
DISPLAY 0.872340 (-1275 4325);
PAINT AQUA (-1275 4325);
DISPLAY INVISIBLE (-1275 4325);
FORCEADD Q_INDUCTOR4P_14..1
(-2925 4025);
FORCEPROP 1 LAST LOCATION PL66
J 0
(-3150 4280);
DISPLAY 0.489362 (-3150 4280);
PAINT SKYBLUE (-3150 4280);
FORCEPROP 0 LAST $SEC 1
J 0
(-3150 4425);
DISPLAY 0.680851 (-3150 4425);
PAINT MONO (-3150 4425);
DISPLAY INVISIBLE (-3150 4425);
FORCEPROP 0 LAST CDS_SEC 1
J 0
(-3150 4425);
DISPLAY 1.021277 (-3150 4425);
DISPLAY INVISIBLE (-3150 4425);
FORCEPROP 0 LASTPIN (-3325 4150) $PN 1
J 2
(-3335 4160);
DISPLAY 0.489362 (-3335 4160);
PAINT MONO (-3335 4160);
FORCEPROP 0 LASTPIN (-3325 3900) $PN 2
J 2
(-3335 3910);
DISPLAY 0.489362 (-3335 3910);
PAINT MONO (-3335 3910);
FORCEPROP 0 LASTPIN (-2525 3900) $PN 3
J 0
(-2515 3910);
DISPLAY 0.489362 (-2515 3910);
PAINT MONO (-2515 3910);
FORCEPROP 0 LASTPIN (-2525 4150) $PN 4
J 0
(-2515 4160);
DISPLAY 0.489362 (-2515 4160);
PAINT MONO (-2515 4160);
FORCEPROP 2 LAST PART_TYPE SMLF
J 0
(-3150 4375);
DISPLAY 1.021277 (-3150 4375);
FORCEPROP 2 LAST VALUE 150NH
J 0
(-3150 4325);
DISPLAY 0.489362 (-3150 4325);
PAINT SKYBLUE (-3150 4325);
FORCEPROP 1 LAST PART_NUMBER CV+15^0TZ04
J 0
(-3150 4185);
DISPLAY 0.489362 (-3150 4185);
PAINT SKYBLUE (-3150 4185);
FORCEPROP 1 LAST MATERIAL IND
J 0
(-3150 4235);
DISPLAY 0.489362 (-3150 4235);
PAINT SKYBLUE (-3150 4235);
FORCEPROP 2 LAST CDS_LIB pure_quanta
J 0
(-2925 4025);
DISPLAY INVISIBLE (-2925 4025);
FORCEPROP 1 LAST NEEDS_NO_SIZE TRUE
J 0
(-2925 4025);
DISPLAY 0.468085 (-2925 4025);
PAINT GREEN (-2925 4025);
DISPLAY INVISIBLE (-2925 4025);
FORCEPROP 1 LAST PATH I31
J 0
(-2725 4180);
DISPLAY 0.723404 (-2725 4180);
PAINT GREEN (-2725 4180);
DISPLAY INVISIBLE (-2725 4180);
FORCEADD Q_CAP..1
(-3700 4375);
FORCEPROP 1 LAST LOCATION PC612
J 0
(-3650 4500);
DISPLAY 0.489362 (-3650 4500);
PAINT SKYBLUE (-3650 4500);
FORCEPROP 0 LAST $SEC 1
J 0
(-3650 4525);
DISPLAY 0.680851 (-3650 4525);
PAINT MONO (-3650 4525);
DISPLAY INVISIBLE (-3650 4525);
FORCEPROP 0 LAST CDS_SEC 1
J 0
(-3650 4525);
DISPLAY 1.021277 (-3650 4525);
DISPLAY INVISIBLE (-3650 4525);
FORCEPROP 1 LASTPIN (-3700 4475) $PN 1
J 0
(-3690 4455);
DISPLAY 0.489362 (-3690 4455);
PAINT MONO (-3690 4455);
FORCEPROP 1 LASTPIN (-3700 4275) $PN 2
J 0
(-3690 4255);
DISPLAY 0.489362 (-3690 4255);
PAINT MONO (-3690 4255);
FORCEPROP 1 LAST MATERIAL X7R
J 0
(-3650 4300);
DISPLAY 0.489362 (-3650 4300);
PAINT SKYBLUE (-3650 4300);
FORCEPROP 1 LAST TOLERANCE 10%
J 0
(-3650 4350);
DISPLAY 0.489362 (-3650 4350);
PAINT SKYBLUE (-3650 4350);
FORCEPROP 1 LAST VALUE 0.22UF
J 0
(-3650 4450);
DISPLAY 0.489362 (-3650 4450);
PAINT SKYBLUE (-3650 4450);
FORCEPROP 1 LAST PART_NUMBER CH4223K1B00
J 0
(-3650 4250);
DISPLAY 0.489362 (-3650 4250);
PAINT SKYBLUE (-3650 4250);
FORCEPROP 1 LAST VOLTAGE 16V
J 0
(-3650 4400);
DISPLAY 0.489362 (-3650 4400);
PAINT SKYBLUE (-3650 4400);
FORCEPROP 1 LAST PACK_TYPE 0402
J 0
(-3650 4200);
DISPLAY 0.489362 (-3650 4200);
PAINT SKYBLUE (-3650 4200);
FORCEPROP 2 LAST CDS_LIB pure_quanta
J 0
(-3700 4375);
DISPLAY INVISIBLE (-3700 4375);
FORCEPROP 1 LAST PATH I32
J 0
(-3650 4525);
DISPLAY 0.978723 (-3650 4525);
PAINT WHITE (-3650 4525);
DISPLAY INVISIBLE (-3650 4525);
FORCEADD Q_CAP..1
(-5025 5025);
FORCEPROP 1 LAST LOCATION PC608_3
J 0
(-4975 5125);
DISPLAY 0.489362 (-4975 5125);
PAINT SKYBLUE (-4975 5125);
FORCEPROP 0 LAST $SEC 1
J 0
(-4975 5175);
DISPLAY 0.680851 (-4975 5175);
PAINT MONO (-4975 5175);
DISPLAY INVISIBLE (-4975 5175);
FORCEPROP 0 LAST CDS_SEC 1
J 0
(-4975 5175);
DISPLAY 1.021277 (-4975 5175);
DISPLAY INVISIBLE (-4975 5175);
FORCEPROP 1 LASTPIN (-5025 5125) $PN 1
J 0
(-5015 5105);
DISPLAY 0.489362 (-5015 5105);
PAINT MONO (-5015 5105);
FORCEPROP 1 LASTPIN (-5025 4925) $PN 2
J 0
(-5015 4905);
DISPLAY 0.489362 (-5015 4905);
PAINT MONO (-5015 4905);
FORCEPROP 1 LAST MATERIAL X7R
J 0
(-4975 4925);
DISPLAY 0.489362 (-4975 4925);
PAINT SKYBLUE (-4975 4925);
FORCEPROP 1 LAST TOLERANCE 10%
J 0
(-4975 4975);
DISPLAY 0.489362 (-4975 4975);
PAINT SKYBLUE (-4975 4975);
FORCEPROP 1 LAST VALUE 0.1UF
J 0
(-4975 5075);
DISPLAY 0.489362 (-4975 5075);
PAINT SKYBLUE (-4975 5075);
FORCEPROP 1 LAST PART_NUMBER CH4104K1B00
J 0
(-4975 4875);
DISPLAY 0.489362 (-4975 4875);
PAINT SKYBLUE (-4975 4875);
FORCEPROP 1 LAST VOLTAGE 25V
J 0
(-4975 5025);
DISPLAY 0.489362 (-4975 5025);
PAINT SKYBLUE (-4975 5025);
FORCEPROP 1 LAST PACK_TYPE 0402
J 0
(-4975 4825);
DISPLAY 0.489362 (-4975 4825);
PAINT SKYBLUE (-4975 4825);
FORCEPROP 2 LAST CDS_LIB pure_quanta
J 0
(-5025 5025);
DISPLAY INVISIBLE (-5025 5025);
FORCEPROP 1 LAST PATH I37
J 0
(-4975 5175);
DISPLAY 0.978723 (-4975 5175);
PAINT WHITE (-4975 5175);
DISPLAY INVISIBLE (-4975 5175);
FORCEADD Q_CAP..1
(-7325 4500);
FORCEPROP 1 LAST LOCATION PC606
J 0
(-7275 4600);
DISPLAY 0.489362 (-7275 4600);
PAINT SKYBLUE (-7275 4600);
FORCEPROP 0 LAST $SEC 1
J 0
(-7275 4650);
DISPLAY 0.680851 (-7275 4650);
PAINT MONO (-7275 4650);
DISPLAY INVISIBLE (-7275 4650);
FORCEPROP 0 LAST CDS_SEC 1
J 0
(-7275 4650);
DISPLAY 1.021277 (-7275 4650);
DISPLAY INVISIBLE (-7275 4650);
FORCEPROP 1 LASTPIN (-7325 4600) $PN 1
J 0
(-7315 4580);
DISPLAY 0.489362 (-7315 4580);
PAINT MONO (-7315 4580);
FORCEPROP 1 LASTPIN (-7325 4400) $PN 2
J 0
(-7315 4380);
DISPLAY 0.489362 (-7315 4380);
PAINT MONO (-7315 4380);
FORCEPROP 1 LAST MATERIAL X6S
J 0
(-7275 4400);
DISPLAY 0.489362 (-7275 4400);
PAINT SKYBLUE (-7275 4400);
FORCEPROP 1 LAST TOLERANCE 10%
J 0
(-7275 4450);
DISPLAY 0.489362 (-7275 4450);
PAINT SKYBLUE (-7275 4450);
FORCEPROP 1 LAST VALUE 2.2UF
J 0
(-7275 4550);
DISPLAY 0.489362 (-7275 4550);
PAINT SKYBLUE (-7275 4550);
FORCEPROP 1 LAST PART_NUMBER CH5222KEB01
J 0
(-7275 4350);
DISPLAY 0.489362 (-7275 4350);
PAINT SKYBLUE (-7275 4350);
FORCEPROP 1 LAST VOLTAGE 10V
J 0
(-7275 4500);
DISPLAY 0.489362 (-7275 4500);
PAINT SKYBLUE (-7275 4500);
FORCEPROP 1 LAST PACK_TYPE C0402
J 0
(-7275 4300);
DISPLAY 0.489362 (-7275 4300);
PAINT SKYBLUE (-7275 4300);
FORCEPROP 2 LAST CDS_LIB pure_quanta
J 0
(-7325 4500);
DISPLAY INVISIBLE (-7325 4500);
FORCEPROP 1 LAST PATH I38
J 0
(-7275 4650);
DISPLAY 0.978723 (-7275 4650);
PAINT WHITE (-7275 4650);
DISPLAY INVISIBLE (-7275 4650);
FORCEADD UNIVERSAL_GND..1
(-7325 4300);
FORCEPROP 3 LASTPIN (-7325 4350) SIG_NAME GND\g
J 0
(-7315 4360);
DISPLAY 0.659574 (-7315 4360);
PAINT MONO (-7315 4360);
DISPLAY INVISIBLE (-7315 4360);
FORCEPROP 2 LAST CDS_LIB pure_quanta_power
J 0
(-7325 4300);
DISPLAY INVISIBLE (-7325 4300);
FORCEPROP 1 LAST PATH I39
J 0
(-7250 4300);
DISPLAY 0.872340 (-7250 4300);
PAINT AQUA (-7250 4300);
DISPLAY INVISIBLE (-7250 4300);
FORCEPROP 1 LAST HDL_POWER GND
J 1
(-7300 4225);
DISPLAY 0.872340 (-7300 4225);
PAINT GREEN (-7300 4225);
DISPLAY INVISIBLE (-7300 4225);
FORCEADD OFFPAGE..2
R 2
(-6950 3650);
FORCEPROP 2 LAST $XR1 169 
J 0
(-7235 3614);
DISPLAY 0.638298 (-7235 3614);
PAINT MONO (-7235 3614);
FORCEPROP 2 LAST $XR0 174 
J 0
(-7235 3650);
DISPLAY 0.638298 (-7235 3650);
PAINT MONO (-7235 3650);
FORCEPROP 2 LAST PATH I4
J 0
(-6900 3725);
DISPLAY 1.021277 (-6900 3725);
DISPLAY INVISIBLE (-6900 3725);
FORCEPROP 1 LAST COMMENT_BODY TRUE
J 2
(-6905 3555);
DISPLAY 0.872340 (-6905 3555);
PAINT GREEN (-6905 3555);
DISPLAY INVISIBLE (-6905 3555);
FORCEPROP 1 LAST OFFPAGE TRUE
J 2
(-7275 3525);
DISPLAY 0.872340 (-7275 3525);
PAINT GREEN (-7275 3525);
DISPLAY INVISIBLE (-7275 3525);
FORCEPROP 2 LAST CDS_LIB standard
J 0
(-6950 3650);
DISPLAY INVISIBLE (-6950 3650);
FORCEADD UNIVERSAL_GND..1
(-6975 4725);
FORCEPROP 3 LASTPIN (-6975 4775) SIG_NAME GND\g
J 0
(-6965 4785);
DISPLAY 0.659574 (-6965 4785);
PAINT MONO (-6965 4785);
DISPLAY INVISIBLE (-6965 4785);
FORCEPROP 2 LAST CDS_LIB pure_quanta_power
J 0
(-6975 4725);
DISPLAY INVISIBLE (-6975 4725);
FORCEPROP 1 LAST PATH I40
J 0
(-6900 4725);
DISPLAY 0.872340 (-6900 4725);
PAINT AQUA (-6900 4725);
DISPLAY INVISIBLE (-6900 4725);
FORCEPROP 1 LAST HDL_POWER GND
J 1
(-6950 4650);
DISPLAY 0.872340 (-6950 4650);
PAINT GREEN (-6950 4650);
DISPLAY INVISIBLE (-6950 4650);
FORCEADD Q_RES..2
(-7325 4975);
FORCEPROP 1 LAST LOCATION PR364
J 0
(-7280 5075);
DISPLAY 0.489362 (-7280 5075);
PAINT SKYBLUE (-7280 5075);
FORCEPROP 0 LAST $SEC 1
J 0
(-7275 5150);
DISPLAY 0.680851 (-7275 5150);
PAINT MONO (-7275 5150);
DISPLAY INVISIBLE (-7275 5150);
FORCEPROP 0 LAST CDS_SEC 1
J 0
(-7275 5150);
DISPLAY 1.021277 (-7275 5150);
DISPLAY INVISIBLE (-7275 5150);
FORCEPROP 1 LASTPIN (-7325 5075) $PN 1
J 0
(-7320 5037);
DISPLAY 0.489362 (-7320 5037);
PAINT MONO (-7320 5037);
FORCEPROP 1 LASTPIN (-7325 4875) $PN 2
J 0
(-7320 4885);
DISPLAY 0.489362 (-7320 4885);
PAINT MONO (-7320 4885);
FORCEPROP 1 LAST WATTAGE 1/16W
J 0
(-7275 4925);
DISPLAY 0.489362 (-7275 4925);
PAINT SKYBLUE (-7275 4925);
FORCEPROP 1 LAST MATERIAL CHIP
J 0
(-7275 4875);
DISPLAY 0.489362 (-7275 4875);
PAINT SKYBLUE (-7275 4875);
FORCEPROP 1 LAST TOLERANCE 1%
J 0
(-7275 4975);
DISPLAY 0.489362 (-7275 4975);
PAINT SKYBLUE (-7275 4975);
FORCEPROP 1 LAST VALUE 2.2
J 0
(-7275 5025);
DISPLAY 0.489362 (-7275 5025);
PAINT SKYBLUE (-7275 5025);
FORCEPROP 1 LAST PART_NUMBER CS-2202FB00
J 0
(-7275 4825);
DISPLAY 0.489362 (-7275 4825);
PAINT SKYBLUE (-7275 4825);
FORCEPROP 1 LAST PACK_TYPE 0402LF
J 0
(-7275 4775);
DISPLAY 0.489362 (-7275 4775);
PAINT SKYBLUE (-7275 4775);
FORCEPROP 2 LAST CDS_LIB pure_quanta
J 0
(-7325 4975);
DISPLAY INVISIBLE (-7325 4975);
FORCEPROP 1 LAST PATH I41
J 0
(-7275 5150);
DISPLAY 0.978723 (-7275 5150);
PAINT WHITE (-7275 5150);
DISPLAY INVISIBLE (-7275 5150);
FORCEADD Q_CAP..1
(-6975 4975);
FORCEPROP 1 LAST LOCATION PC607_SOP0_3
J 0
(-6925 5075);
DISPLAY 0.489362 (-6925 5075);
PAINT SKYBLUE (-6925 5075);
FORCEPROP 0 LAST $SEC 1
J 0
(-6925 5125);
DISPLAY 0.680851 (-6925 5125);
PAINT MONO (-6925 5125);
DISPLAY INVISIBLE (-6925 5125);
FORCEPROP 0 LAST CDS_SEC 1
J 0
(-6925 5125);
DISPLAY 1.021277 (-6925 5125);
DISPLAY INVISIBLE (-6925 5125);
FORCEPROP 1 LASTPIN (-6975 5075) $PN 1
J 0
(-6965 5055);
DISPLAY 0.489362 (-6965 5055);
PAINT MONO (-6965 5055);
FORCEPROP 1 LASTPIN (-6975 4875) $PN 2
J 0
(-6965 4855);
DISPLAY 0.489362 (-6965 4855);
PAINT MONO (-6965 4855);
FORCEPROP 1 LAST MATERIAL X6S
J 0
(-6925 4875);
DISPLAY 0.489362 (-6925 4875);
PAINT SKYBLUE (-6925 4875);
FORCEPROP 1 LAST TOLERANCE 10%
J 0
(-6925 4925);
DISPLAY 0.489362 (-6925 4925);
PAINT SKYBLUE (-6925 4925);
FORCEPROP 1 LAST VALUE 2.2UF
J 0
(-6925 5025);
DISPLAY 0.489362 (-6925 5025);
PAINT SKYBLUE (-6925 5025);
FORCEPROP 1 LAST PART_NUMBER CH5222KEB01
J 0
(-6925 4825);
DISPLAY 0.489362 (-6925 4825);
PAINT SKYBLUE (-6925 4825);
FORCEPROP 1 LAST VOLTAGE 10V
J 0
(-6925 4975);
DISPLAY 0.489362 (-6925 4975);
PAINT SKYBLUE (-6925 4975);
FORCEPROP 1 LAST PACK_TYPE C0402
J 0
(-6925 4775);
DISPLAY 0.489362 (-6925 4775);
PAINT SKYBLUE (-6925 4775);
FORCEPROP 2 LAST CDS_LIB pure_quanta
J 0
(-6975 4975);
DISPLAY INVISIBLE (-6975 4975);
FORCEPROP 1 LAST PATH I42
J 0
(-6925 5125);
DISPLAY 0.978723 (-6925 5125);
PAINT WHITE (-6925 5125);
DISPLAY INVISIBLE (-6925 5125);
FORCEADD ISL99390FRZTR5935..1
(-5825 4150);
FORCEPROP 1 LAST LOCATION PU51
J 0
(-6125 5025);
DISPLAY 0.489362 (-6125 5025);
PAINT SKYBLUE (-6125 5025);
FORCEPROP 0 LAST $SEC 1
J 0
(-6125 5175);
DISPLAY 0.680851 (-6125 5175);
PAINT MONO (-6125 5175);
DISPLAY INVISIBLE (-6125 5175);
FORCEPROP 0 LAST CDS_SEC 1
J 0
(-6125 5175);
DISPLAY 1.021277 (-6125 5175);
DISPLAY INVISIBLE (-6125 5175);
FORCEPROP 0 LASTPIN (-5425 3700) $PN 2
J 0
(-5415 3710);
DISPLAY 0.489362 (-5415 3710);
PAINT MONO (-5415 3710);
FORCEPROP 0 LASTPIN (-5425 4500) $PN 33
J 0
(-5415 4510);
DISPLAY 0.489362 (-5415 4510);
PAINT MONO (-5415 4510);
FORCEPROP 0 LASTPIN (-6275 3900) $PN 31
J 2
(-6285 3910);
DISPLAY 0.489362 (-6285 3910);
PAINT MONO (-6285 3910);
FORCEPROP 0 LASTPIN (-6275 4300) $PN 35
J 2
(-6285 4310);
DISPLAY 0.489362 (-6285 4310);
PAINT MONO (-6285 4310);
FORCEPROP 0 LASTPIN (-5425 3850) $PN 6
J 0
(-5415 3860);
DISPLAY 0.489362 (-5415 3860);
PAINT MONO (-5415 3860);
FORCEPROP 0 LASTPIN (-5425 3800) $PN 41
J 0
(-5415 3810);
DISPLAY 0.489362 (-5415 3810);
PAINT MONO (-5415 3810);
FORCEPROP 0 LASTPIN (-6275 4150) $PN 38
J 2
(-6285 4160);
DISPLAY 0.489362 (-6285 4160);
PAINT MONO (-6285 4160);
FORCEPROP 0 LASTPIN (-6275 3850) $PN 37
J 2
(-6285 3860);
DISPLAY 0.489362 (-6285 3860);
PAINT MONO (-6285 3860);
FORCEPROP 0 LASTPIN (-5425 3650) $PN 5
J 0
(-5415 3660);
DISPLAY 0.489362 (-5415 3660);
PAINT MONO (-5415 3660);
FORCEPROP 0 LASTPIN (-5425 3600) $PN 7_9-20_24
J 0
(-5415 3610);
DISPLAY 0.489362 (-5415 3610);
PAINT MONO (-5415 3610);
FORCEPROP 0 LASTPIN (-5425 3550) $PN 40
J 0
(-5415 3560);
DISPLAY 0.489362 (-5415 3560);
PAINT MONO (-5415 3560);
FORCEPROP 0 LASTPIN (-5425 4250) $PN 32
J 0
(-5415 4260);
DISPLAY 0.489362 (-5415 4260);
PAINT MONO (-5415 4260);
FORCEPROP 0 LASTPIN (-6275 4800) $PN 4
J 2
(-6285 4810);
DISPLAY 0.489362 (-6285 4810);
PAINT MONO (-6285 4810);
FORCEPROP 0 LASTPIN (-6275 3550) $PN 34
J 2
(-6285 3560);
DISPLAY 0.489362 (-6285 3560);
PAINT MONO (-6285 3560);
FORCEPROP 0 LASTPIN (-6275 4050) $PN 39
J 2
(-6285 4060);
DISPLAY 0.489362 (-6285 4060);
PAINT MONO (-6285 4060);
FORCEPROP 0 LASTPIN (-5425 4150) $PN 10_19
J 0
(-5415 4160);
DISPLAY 0.489362 (-5415 4160);
PAINT MONO (-5415 4160);
FORCEPROP 0 LASTPIN (-6275 3650) $PN 36
J 2
(-6285 3660);
DISPLAY 0.489362 (-6285 3660);
PAINT MONO (-6285 3660);
FORCEPROP 0 LASTPIN (-6275 4500) $PN 3
J 2
(-6285 4510);
DISPLAY 0.489362 (-6285 4510);
PAINT MONO (-6285 4510);
FORCEPROP 0 LASTPIN (-5425 4800) $PN 25_29
J 0
(-5415 4810);
DISPLAY 0.489362 (-5415 4810);
PAINT MONO (-5415 4810);
FORCEPROP 0 LASTPIN (-5425 4750) $PN 30
J 0
(-5415 4760);
DISPLAY 0.489362 (-5415 4760);
PAINT MONO (-5415 4760);
FORCEPROP 0 LASTPIN (-5425 3900) $PN 1
J 0
(-5415 3910);
DISPLAY 0.489362 (-5415 3910);
PAINT MONO (-5415 3910);
FORCEPROP 2 LAST PART_TYPE SMLF
J 0
(-6125 5125);
DISPLAY 1.021277 (-6125 5125);
FORCEPROP 1 LAST MATERIAL IC
J 0
(-6125 4875);
DISPLAY 0.489362 (-6125 4875);
PAINT SKYBLUE (-6125 4875);
FORCEPROP 2 LAST VALUE ISL99390FRZ-TR5935
J 0
(-6125 5075);
DISPLAY 0.489362 (-6125 5075);
PAINT SKYBLUE (-6125 5075);
FORCEPROP 1 LAST PART_NUMBER AL099390004
J 0
(-6125 4950);
DISPLAY 0.489362 (-6125 4950);
PAINT SKYBLUE (-6125 4950);
FORCEPROP 2 LAST CDS_LIB pure_quanta
J 0
(-5825 4150);
DISPLAY INVISIBLE (-5825 4150);
FORCEPROP 1 LAST NEEDS_NO_SIZE TRUE
J 0
(-5825 4150);
DISPLAY 0.723404 (-5825 4150);
PAINT GREEN (-5825 4150);
DISPLAY INVISIBLE (-5825 4150);
FORCEPROP 1 LAST CDS_LMAN_SYM_OUTLINE -300,700,250,-650
J 0
(-5825 4150);
DISPLAY 0.468085 (-5825 4150);
PAINT GREEN (-5825 4150);
DISPLAY INVISIBLE (-5825 4150);
FORCEPROP 1 LAST PATH I44
J 0
(-5825 4150);
DISPLAY 0.723404 (-5825 4150);
PAINT GREEN (-5825 4150);
DISPLAY INVISIBLE (-5825 4150);
FORCEADD Q_CAP..1
(-4475 3975);
FORCEPROP 1 LAST LOCATION PC188
J 0
(-4425 4075);
DISPLAY 0.489362 (-4425 4075);
PAINT SKYBLUE (-4425 4075);
FORCEPROP 0 LAST $SEC 1
J 0
(-4425 4125);
DISPLAY 0.680851 (-4425 4125);
PAINT MONO (-4425 4125);
DISPLAY INVISIBLE (-4425 4125);
FORCEPROP 0 LAST CDS_SEC 1
J 0
(-4425 4125);
DISPLAY 1.021277 (-4425 4125);
DISPLAY INVISIBLE (-4425 4125);
FORCEPROP 1 LASTPIN (-4475 4075) $PN 1
J 0
(-4465 4055);
DISPLAY 0.489362 (-4465 4055);
PAINT MONO (-4465 4055);
FORCEPROP 1 LASTPIN (-4475 3875) $PN 2
J 0
(-4465 3855);
DISPLAY 0.489362 (-4465 3855);
PAINT MONO (-4465 3855);
FORCEPROP 1 LAST TOLERANCE 10%
J 0
(-4425 3925);
DISPLAY 0.489362 (-4425 3925);
PAINT SKYBLUE (-4425 3925);
FORCEPROP 1 LAST VALUE 560PF
J 0
(-4425 4025);
DISPLAY 0.489362 (-4425 4025);
PAINT SKYBLUE (-4425 4025);
FORCEPROP 1 LAST VOLTAGE 50V
J 0
(-4425 3975);
DISPLAY 0.489362 (-4425 3975);
PAINT SKYBLUE (-4425 3975);
FORCEPROP 1 LAST MATERIAL EMPTY
J 0
(-4425 3875);
DISPLAY 0.489362 (-4425 3875);
PAINT RED (-4425 3875);
FORCEPROP 1 LAST PACK_TYPE C0402
J 0
(-4425 3775);
DISPLAY 0.489362 (-4425 3775);
PAINT SKYBLUE (-4425 3775);
FORCEPROP 1 LAST PART_NUMBER CH1566K1B09
J 0
(-4425 3825);
DISPLAY 0.489362 (-4425 3825);
PAINT SKYBLUE (-4425 3825);
FORCEPROP 2 LAST CDS_LIB pure_quanta
J 0
(-4475 3975);
DISPLAY INVISIBLE (-4475 3975);
FORCEPROP 1 LAST PATH I46
J 0
(-4425 4125);
DISPLAY 0.978723 (-4425 4125);
PAINT WHITE (-4425 4125);
DISPLAY INVISIBLE (-4425 4125);
FORCEADD Q_RES..2
(-4475 3500);
FORCEPROP 1 LAST LOCATION PR505
J 0
(-4430 3625);
DISPLAY 0.489362 (-4430 3625);
PAINT SKYBLUE (-4430 3625);
FORCEPROP 0 LAST $SEC 1
J 0
(-4425 3675);
DISPLAY 0.680851 (-4425 3675);
PAINT MONO (-4425 3675);
DISPLAY INVISIBLE (-4425 3675);
FORCEPROP 0 LAST CDS_SEC 1
J 0
(-4425 3675);
DISPLAY 1.021277 (-4425 3675);
DISPLAY INVISIBLE (-4425 3675);
FORCEPROP 1 LASTPIN (-4475 3600) $PN 1
J 0
(-4470 3562);
DISPLAY 0.489362 (-4470 3562);
PAINT MONO (-4470 3562);
FORCEPROP 1 LASTPIN (-4475 3400) $PN 2
J 0
(-4470 3410);
DISPLAY 0.489362 (-4470 3410);
PAINT MONO (-4470 3410);
FORCEPROP 1 LAST WATTAGE 1/8W
J 0
(-4435 3475);
DISPLAY 0.489362 (-4435 3475);
PAINT SKYBLUE (-4435 3475);
FORCEPROP 1 LAST MATERIAL EMPTY
J 0
(-4435 3425);
DISPLAY 0.489362 (-4435 3425);
PAINT RED (-4435 3425);
FORCEPROP 1 LAST TOLERANCE 1%
J 0
(-4430 3525);
DISPLAY 0.489362 (-4430 3525);
PAINT SKYBLUE (-4430 3525);
FORCEPROP 1 LAST VALUE 1.5
J 0
(-4430 3575);
DISPLAY 0.489362 (-4430 3575);
PAINT SKYBLUE (-4430 3575);
FORCEPROP 1 LAST PART_NUMBER CS-1504FB00
J 0
(-4435 3375);
DISPLAY 0.489362 (-4435 3375);
PAINT SKYBLUE (-4435 3375);
FORCEPROP 1 LAST PACK_TYPE 0402LF
J 0
(-4435 3325);
DISPLAY 0.489362 (-4435 3325);
PAINT SKYBLUE (-4435 3325);
FORCEPROP 2 LAST CDS_LIB pure_quanta
J 0
(-4475 3500);
DISPLAY INVISIBLE (-4475 3500);
FORCEPROP 1 LAST PATH I47
J 0
(-4425 3675);
DISPLAY 0.978723 (-4425 3675);
PAINT WHITE (-4425 3675);
DISPLAY INVISIBLE (-4425 3675);
FORCEADD UNIVERSAL_GND..1
(-4475 3275);
FORCEPROP 3 LASTPIN (-4475 3325) SIG_NAME GND\g
J 0
(-4465 3335);
DISPLAY 0.659574 (-4465 3335);
PAINT MONO (-4465 3335);
DISPLAY INVISIBLE (-4465 3335);
FORCEPROP 2 LAST CDS_LIB pure_quanta_power
J 0
(-4475 3275);
DISPLAY INVISIBLE (-4475 3275);
FORCEPROP 1 LAST PATH I48
J 0
(-4400 3275);
DISPLAY 0.872340 (-4400 3275);
PAINT AQUA (-4400 3275);
DISPLAY INVISIBLE (-4400 3275);
FORCEPROP 1 LAST HDL_POWER GND
J 1
(-4450 3200);
DISPLAY 0.872340 (-4450 3200);
PAINT GREEN (-4450 3200);
DISPLAY INVISIBLE (-4450 3200);
FORCEADD VCC_CORE..1
(-7325 5375);
FORCEPROP 3 LASTPIN (-7325 5325) SIG_NAME PVDDCR_CPU0_P0_PVCC\g
J 0
(-7315 5335);
DISPLAY 0.659574 (-7315 5335);
PAINT MONO (-7315 5335);
DISPLAY INVISIBLE (-7315 5335);
FORCEPROP 1 LAST HDL_POWER PVDDCR_CPU0_P0_PVCC
J 1
(-7325 5425);
DISPLAY 0.489362 (-7325 5425);
PAINT GREEN (-7325 5425);
FORCEPROP 2 LAST CDS_LIB pure_quanta_power
J 0
(-7325 5375);
DISPLAY INVISIBLE (-7325 5375);
FORCEPROP 1 LAST PATH I49
J 0
(-7275 5400);
DISPLAY 0.872340 (-7275 5400);
PAINT AQUA (-7275 5400);
DISPLAY INVISIBLE (-7275 5400);
FORCEADD OFFPAGE..1
(-6925 3550);
FORCEPROP 2 LAST $XR0 169 
J 0
(-7207 3550);
DISPLAY 0.638298 (-7207 3550);
PAINT MONO (-7207 3550);
FORCEPROP 2 LAST PATH I5
J 0
(-6875 3625);
DISPLAY 1.021277 (-6875 3625);
DISPLAY INVISIBLE (-6875 3625);
FORCEPROP 1 LAST COMMENT_BODY TRUE
J 0
(-6800 3450);
DISPLAY 0.872340 (-6800 3450);
PAINT GREEN (-6800 3450);
DISPLAY INVISIBLE (-6800 3450);
FORCEPROP 1 LAST OFFPAGE TRUE
J 0
(-6600 3425);
DISPLAY 0.872340 (-6600 3425);
PAINT GREEN (-6600 3425);
DISPLAY INVISIBLE (-6600 3425);
FORCEPROP 2 LAST CDS_LIB standard
J 2
(-6925 3550);
DISPLAY INVISIBLE (-6925 3550);
FORCEADD Q_CAP..1
(-3325 5025);
FORCEPROP 1 LAST LOCATION PC612_3
J 0
(-3275 5125);
DISPLAY 0.489362 (-3275 5125);
PAINT SKYBLUE (-3275 5125);
FORCEPROP 0 LAST $SEC 1
J 0
(-3275 5150);
DISPLAY 0.680851 (-3275 5150);
PAINT MONO (-3275 5150);
DISPLAY INVISIBLE (-3275 5150);
FORCEPROP 0 LAST CDS_SEC 1
J 0
(-3275 5150);
DISPLAY 0.680851 (-3275 5150);
DISPLAY INVISIBLE (-3275 5150);
FORCEPROP 1 LASTPIN (-3325 5125) $PN 1
J 0
(-3315 5105);
DISPLAY 0.787234 (-3315 5105);
PAINT MONO (-3315 5105);
DISPLAY INVISIBLE (-3315 5105);
FORCEPROP 1 LASTPIN (-3325 4925) $PN 2
J 0
(-3315 4905);
DISPLAY 0.787234 (-3315 4905);
PAINT MONO (-3315 4905);
DISPLAY INVISIBLE (-3315 4905);
FORCEPROP 1 LAST MATERIAL X6S
J 0
(-3275 4925);
DISPLAY 0.489362 (-3275 4925);
PAINT SKYBLUE (-3275 4925);
FORCEPROP 1 LAST TOLERANCE 10%
J 0
(-3275 4975);
DISPLAY 0.489362 (-3275 4975);
PAINT SKYBLUE (-3275 4975);
FORCEPROP 1 LAST VALUE 10UF
J 0
(-3275 5075);
DISPLAY 0.489362 (-3275 5075);
PAINT SKYBLUE (-3275 5075);
FORCEPROP 1 LAST PART_NUMBER CH6104KEA00
J 0
(-3275 4875);
DISPLAY 0.489362 (-3275 4875);
PAINT SKYBLUE (-3275 4875);
FORCEPROP 1 LAST VOLTAGE 25V
J 0
(-3275 5025);
DISPLAY 0.489362 (-3275 5025);
PAINT SKYBLUE (-3275 5025);
FORCEPROP 1 LAST PACK_TYPE C0805
J 0
(-3275 4825);
DISPLAY 0.489362 (-3275 4825);
PAINT SKYBLUE (-3275 4825);
FORCEPROP 2 LAST CDS_LIB pure_quanta
J 0
(-3325 5025);
DISPLAY INVISIBLE (-3325 5025);
FORCEPROP 1 LAST PATH I50
J 0
(-3275 5175);
DISPLAY 0.978723 (-3275 5175);
PAINT WHITE (-3275 5175);
DISPLAY INVISIBLE (-3275 5175);
FORCEADD Q_INDUCTOR..1
(-3875 3925);
FORCEPROP 1 LAST LOCATION PL62
J 0
(-4025 4050);
DISPLAY 0.468085 (-4025 4050);
PAINT SKYBLUE (-4025 4050);
FORCEPROP 0 LAST $SEC 1
J 0
(-4025 4150);
DISPLAY 0.680851 (-4025 4150);
PAINT MONO (-4025 4150);
DISPLAY INVISIBLE (-4025 4150);
FORCEPROP 0 LAST CDS_SEC 1
J 0
(-4025 4100);
DISPLAY 0.680851 (-4025 4100);
DISPLAY INVISIBLE (-4025 4100);
FORCEPROP 0 LASTPIN (-3975 3900) $PN 1
J 2
(-3985 3910);
DISPLAY 0.680851 (-3985 3910);
PAINT MONO (-3985 3910);
FORCEPROP 0 LASTPIN (-3775 3900) $PN 2
J 0
(-3765 3910);
DISPLAY 0.680851 (-3765 3910);
PAINT MONO (-3765 3910);
FORCEPROP 1 LAST MATERIAL IND
J 0
(-4025 4000);
DISPLAY 0.468085 (-4025 4000);
PAINT SKYBLUE (-4025 4000);
FORCEPROP 2 LAST VALUE 0.22UH/33A
J 0
(-4025 4025);
DISPLAY 0.489362 (-4025 4025);
PAINT SKYBLUE (-4025 4025);
FORCEPROP 1 LAST PART_NUMBER CV+22Y0EZ00
J 0
(-4025 3975);
DISPLAY 0.468085 (-4025 3975);
PAINT SKYBLUE (-4025 3975);
FORCEPROP 2 LAST PACK_TYPE SMLF
J 0
(-4025 4100);
DISPLAY 0.765957 (-4025 4100);
FORCEPROP 1 LAST NEEDS_NO_SIZE TRUE
J 0
(-3875 3925);
DISPLAY 0.468085 (-3875 3925);
PAINT GREEN (-3875 3925);
DISPLAY INVISIBLE (-3875 3925);
FORCEPROP 1 LAST PATH I51
J 0
(-3800 3980);
DISPLAY 0.723404 (-3800 3980);
PAINT GREEN (-3800 3980);
DISPLAY INVISIBLE (-3800 3980);
FORCEPROP 2 LAST CDS_LIB pure_quanta
J 0
(-3875 3925);
DISPLAY INVISIBLE (-3875 3925);
FORCEADD UNIVERSAL_GND..1
(-4075 3800);
FORCEPROP 3 LASTPIN (-4075 3850) SIG_NAME GND\g
J 0
(-4065 3860);
DISPLAY 0.659574 (-4065 3860);
PAINT MONO (-4065 3860);
DISPLAY INVISIBLE (-4065 3860);
FORCEPROP 2 LAST CDS_LIB pure_quanta_power
J 0
(-4075 3800);
DISPLAY INVISIBLE (-4075 3800);
FORCEPROP 1 LAST PATH I52
J 0
(-4000 3800);
DISPLAY 0.872340 (-4000 3800);
PAINT AQUA (-4000 3800);
DISPLAY INVISIBLE (-4000 3800);
FORCEPROP 1 LAST HDL_POWER GND
J 1
(-4050 3725);
DISPLAY 0.872340 (-4050 3725);
PAINT GREEN (-4050 3725);
DISPLAY INVISIBLE (-4050 3725);
FORCEADD OFFPAGE..3
(-2050 3900);
FORCEPROP 2 LAST $XR0 174 
J 0
(-1626 3900);
DISPLAY 0.638298 (-1626 3900);
PAINT MONO (-1626 3900);
FORCEPROP 2 LAST CDS_LIB standard
J 2
(-2050 3900);
DISPLAY INVISIBLE (-2050 3900);
FORCEPROP 1 LAST OFFPAGE TRUE
J 0
(-1725 3775);
DISPLAY 0.872340 (-1725 3775);
PAINT GREEN (-1725 3775);
DISPLAY INVISIBLE (-1725 3775);
FORCEPROP 1 LAST COMMENT_BODY TRUE
J 0
(-2100 3800);
DISPLAY 0.872340 (-2100 3800);
PAINT GREEN (-2100 3800);
DISPLAY INVISIBLE (-2100 3800);
FORCEPROP 2 LAST PATH I53
J 0
(-1925 4000);
DISPLAY 1.021277 (-1925 4000);
DISPLAY INVISIBLE (-1925 4000);
FORCEADD Q_CAP..1
(-7650 3875);
FORCEPROP 1 LAST LOCATION PC605_9
J 0
(-7600 3975);
DISPLAY 0.489362 (-7600 3975);
PAINT SKYBLUE (-7600 3975);
FORCEPROP 0 LAST $SEC 1
J 0
(-7600 4000);
DISPLAY 0.680851 (-7600 4000);
PAINT MONO (-7600 4000);
DISPLAY INVISIBLE (-7600 4000);
FORCEPROP 0 LAST CDS_SEC 1
J 0
(-7600 4000);
DISPLAY 1.021277 (-7600 4000);
DISPLAY INVISIBLE (-7600 4000);
FORCEPROP 1 LASTPIN (-7650 3975) $PN 1
J 0
(-7640 3955);
DISPLAY 0.489362 (-7640 3955);
PAINT MONO (-7640 3955);
FORCEPROP 1 LASTPIN (-7650 3775) $PN 2
J 0
(-7640 3755);
DISPLAY 0.489362 (-7640 3755);
PAINT MONO (-7640 3755);
FORCEPROP 1 LAST MATERIAL X7R
J 0
(-7600 3775);
DISPLAY 0.489362 (-7600 3775);
PAINT SKYBLUE (-7600 3775);
FORCEPROP 1 LAST TOLERANCE 10%
J 0
(-7600 3825);
DISPLAY 0.489362 (-7600 3825);
PAINT SKYBLUE (-7600 3825);
FORCEPROP 1 LAST VALUE 0.1UF
J 0
(-7600 3925);
DISPLAY 0.489362 (-7600 3925);
PAINT SKYBLUE (-7600 3925);
FORCEPROP 1 LAST PART_NUMBER CH4104K1B00
J 0
(-7600 3725);
DISPLAY 0.489362 (-7600 3725);
PAINT SKYBLUE (-7600 3725);
FORCEPROP 1 LAST VOLTAGE 25V
J 0
(-7600 3875);
DISPLAY 0.489362 (-7600 3875);
PAINT SKYBLUE (-7600 3875);
FORCEPROP 1 LAST PACK_TYPE 0402
J 0
(-7600 3675);
DISPLAY 0.489362 (-7600 3675);
PAINT SKYBLUE (-7600 3675);
FORCEPROP 2 LAST CDS_LIB pure_quanta
J 0
(-7650 3875);
DISPLAY INVISIBLE (-7650 3875);
FORCEPROP 1 LAST PATH I6
J 0
(-7600 4025);
DISPLAY 0.978723 (-7600 4025);
PAINT WHITE (-7600 4025);
DISPLAY INVISIBLE (-7600 4025);
FORCEADD Q_RES..1
(-7000 3850);
FORCEPROP 1 LAST LOCATION PR365
J 0
(-7050 3900);
DISPLAY 0.489362 (-7050 3900);
PAINT SKYBLUE (-7050 3900);
FORCEPROP 0 LAST $SEC 1
J 0
(-7000 3925);
DISPLAY 0.680851 (-7000 3925);
PAINT MONO (-7000 3925);
DISPLAY INVISIBLE (-7000 3925);
FORCEPROP 0 LAST CDS_SEC 1
J 0
(-7000 3925);
DISPLAY 1.021277 (-7000 3925);
DISPLAY INVISIBLE (-7000 3925);
FORCEPROP 1 LASTPIN (-7100 3850) $PN 1
J 0
(-7088 3862);
DISPLAY 0.489362 (-7088 3862);
PAINT MONO (-7088 3862);
FORCEPROP 1 LASTPIN (-6900 3850) $PN 2
J 0
(-6938 3862);
DISPLAY 0.489362 (-6938 3862);
PAINT MONO (-6938 3862);
FORCEPROP 1 LAST WATTAGE 1/16W
J 0
(-6900 3750);
DISPLAY 0.489362 (-6900 3750);
PAINT SKYBLUE (-6900 3750);
FORCEPROP 1 LAST MATERIAL EMPTY
J 0
(-7300 3750);
DISPLAY 0.489362 (-7300 3750);
PAINT RED (-7300 3750);
FORCEPROP 1 LAST TOLERANCE 1%
J 0
(-6875 3875);
DISPLAY 0.489362 (-6875 3875);
PAINT SKYBLUE (-6875 3875);
FORCEPROP 1 LAST VALUE 8.87K
J 2
(-7125 3875);
DISPLAY 0.489362 (-7125 3875);
PAINT SKYBLUE (-7125 3875);
FORCEPROP 1 LAST PART_NUMBER CS28872FB01
J 0
(-7300 3800);
DISPLAY 0.489362 (-7300 3800);
PAINT SKYBLUE (-7300 3800);
FORCEPROP 1 LAST PACK_TYPE 0402LF
J 0
(-6900 3800);
DISPLAY 0.489362 (-6900 3800);
PAINT SKYBLUE (-6900 3800);
FORCEPROP 2 LAST CDS_LIB pure_quanta
J 0
(-7000 3850);
DISPLAY INVISIBLE (-7000 3850);
FORCEPROP 1 LAST PATH I7
J 0
(-7050 4000);
DISPLAY 0.978723 (-7050 4000);
PAINT WHITE (-7050 4000);
DISPLAY INVISIBLE (-7050 4000);
FORCEADD OFFPAGE..2
R 2
(-6975 4150);
FORCEPROP 2 LAST $XR0 169 
J 0
(-7230 4150);
DISPLAY 0.638298 (-7230 4150);
PAINT MONO (-7230 4150);
FORCEPROP 2 LAST PATH I8
J 0
(-6925 4225);
DISPLAY 1.021277 (-6925 4225);
DISPLAY INVISIBLE (-6925 4225);
FORCEPROP 1 LAST COMMENT_BODY TRUE
J 2
(-6930 4055);
DISPLAY 0.872340 (-6930 4055);
PAINT GREEN (-6930 4055);
DISPLAY INVISIBLE (-6930 4055);
FORCEPROP 1 LAST OFFPAGE TRUE
J 2
(-7300 4025);
DISPLAY 0.872340 (-7300 4025);
PAINT GREEN (-7300 4025);
DISPLAY INVISIBLE (-7300 4025);
FORCEPROP 2 LAST CDS_LIB standard
J 2
(-6975 4150);
DISPLAY INVISIBLE (-6975 4150);
FORCEADD DNS..1
(-4500 3975);
PAINT RED (-4500 3975);
FORCEPROP 2 LAST CDS_LIB mstr_misc
J 0
(-4500 3975);
DISPLAY INVISIBLE (-4500 3975);
FORCEPROP 1 LAST COMMENT_BODY TRUE
R 1
J 0
(-4425 3750);
DISPLAY 0.872340 (-4425 3750);
PAINT GREEN (-4425 3750);
DISPLAY INVISIBLE (-4425 3750);
FORCEADD QUANTA_TITLE_BLOCK_C..1
(0 0);
FORCEPROP 0 LAST CDS_CON_LAST_MODIFIED Fri Mar 11 14:53:26 2022
J 0
(-1885 15);
DISPLAY INVISIBLE (-1885 15);
FORCEPROP 1 LAST CUSTOM_TXT_CDS <CON_LAST_MODIFIED>
J 0
(-1885 15);
DISPLAY 0.978723 (-1885 15);
FORCEPROP 2 LAST CUSTOM_TXT_CDS <XR_PAGE_TITLE>
J 0
(-7890 5250);
DISPLAY 0.638298 (-7890 5250);
PAINT PINK (-7890 5250);
DISPLAY INVISIBLE (-7890 5250);
FORCEPROP 1 LAST CUSTOM_TXT_CDS <NAME_2>
J 0
(-3175 50);
FORCEPROP 1 LAST CUSTOM_TXT_CDS <NAME_1>
J 0
(-3175 175);
FORCEPROP 1 LAST CUSTOM_TXT_CDS <Q_NUMBER>
J 0
(-1403 103);
DISPLAY 1.212766 (-1403 103);
FORCEPROP 1 LAST CUSTOM_TXT_CDS <Q_PROJ>
J 0
(-2382 102);
DISPLAY 1.212766 (-2382 102);
FORCEPROP 1 LAST CUSTOM_TXT_CDS <Q_REV>
J 0
(-184 103);
DISPLAY 1.212766 (-184 103);
FORCEPROP 1 LAST CUSTOM_TXT_CDS <CON_PAGE_NUM> OF <CON_TOTAL_PAGES>
J 0
(-446 18);
DISPLAY 0.978723 (-446 18);
FORCEPROP 1 LAST Q_DEPT BU9
J 1
(-3763 49);
DISPLAY 1.957447 (-3763 49);
PAINT GREEN (-3763 49);
FORCEPROP 1 LAST Q_TITLE PVDDCR_SOC_P0 VR PHASE 3
J 0
(-9325 25);
DISPLAY 2.446809 (-9325 25);
PAINT GREEN (-9325 25);
FORCEPROP 1 LAST CDS_LMAN_SYM_OUTLINE -9475,6775,100,-125
J 0
(0 0);
DISPLAY 0.468085 (0 0);
PAINT GREEN (0 0);
DISPLAY INVISIBLE (0 0);
FORCEPROP 2 LAST CDS_LIB pure_quanta
J 0
(0 0);
DISPLAY INVISIBLE (0 0);
FORCEPROP 2 LAST PAGE_BORDER TRUE
J 0
(-7890 5250);
DISPLAY 0.638298 (-7890 5250);
PAINT PINK (-7890 5250);
DISPLAY INVISIBLE (-7890 5250);
FORCEPROP 1 LAST COMMENT_BODY TRUE
J 0
(12 -13);
DISPLAY 0.978723 (12 -13);
PAINT GREEN (12 -13);
DISPLAY INVISIBLE (12 -13);
FORCEPROP 2 LAST CDS_XR_PAGE_TITLE CR-175 : @T6G_MB_LIB.T6G(SCH_1):PAGE175
J 0
(-7890 5250);
DISPLAY 0.638298 (-7890 5250);
PAINT PINK (-7890 5250);
DISPLAY INVISIBLE (-7890 5250);
FORCEADD DNS..1
(-7000 3825);
PAINT RED (-7000 3825);
FORCEPROP 2 LAST CDS_LIB mstr_misc
J 0
(-7000 3825);
DISPLAY INVISIBLE (-7000 3825);
FORCEPROP 1 LAST COMMENT_BODY TRUE
R 1
J 0
(-6925 3600);
DISPLAY 0.872340 (-6925 3600);
PAINT GREEN (-6925 3600);
DISPLAY INVISIBLE (-6925 3600);
FORCEADD DNS..1
(-4500 3500);
PAINT RED (-4500 3500);
FORCEPROP 2 LAST CDS_LIB mstr_misc
J 0
(-4500 3500);
DISPLAY INVISIBLE (-4500 3500);
FORCEPROP 1 LAST COMMENT_BODY TRUE
R 1
J 0
(-4425 3275);
DISPLAY 0.872340 (-4425 3275);
PAINT GREEN (-4425 3275);
DISPLAY INVISIBLE (-4425 3275);
WIRE 16 -1 (-7650 3775)(-7650 3650);
WIRE 16 -1 (-7100 3850)(-7325 3850);
WIRE 16 -1 (-7325 3850)(-7325 3725);
WIRE 16 -1 (-7325 4400)(-7325 4350);
WIRE 16 -1 (-6975 4875)(-6975 4775);
WIRE 16 -1 (-4475 3400)(-4475 3325);
WIRE 16 -1 (-4475 3875)(-4475 3600);
FORCEPROP 2 LAST SIG_NAME SW_PVDDCR_SOC_P0_SW3_RC
J 0
(-4435 3710);
DISPLAY 0.489362 (-4435 3710);
FORCEPROP 2 LASTPROP $XRERR UNIQUE?
J 0
(-4675 3710);
DISPLAY 0.638298 (-4675 3710);
PAINT MONO (-4675 3710);
DISPLAY INVISIBLE (-4675 3710);
WIRE 16 -1 (-4150 3200)(-4700 3200);
FORCEPROP 2 LAST SIG_NAME PVDDCR_SOC_P0_VOS3
J 0
(-5310 3925);
DISPLAY 0.489362 (-5310 3925);
FORCEPROP 2 LASTPROP $XRERR UNIQUE?
J 0
(-5550 3925);
DISPLAY 0.638298 (-5550 3925);
PAINT MONO (-5550 3925);
DISPLAY INVISIBLE (-5550 3925);
WIRE 16 -1 (-4700 3200)(-4700 3900);
WIRE 16 -1 (-5425 3900)(-4700 3900);
WIRE 16 -1 (-5425 3800)(-4900 3800);
FORCEPROP 2 LAST SIG_NAME NC_PVDDCR_SOC_P0_GL2_3
J 0
(-5310 3810);
DISPLAY 0.489362 (-5310 3810);
FORCEPROP 2 LASTPROP $XRERR UNIQUE?
J 0
(-4870 3800);
DISPLAY 0.638298 (-4870 3800);
PAINT MONO (-4870 3800);
DISPLAY INVISIBLE (-4870 3800);
WIRE 16 -1 (-3775 3900)(-3325 3900);
FORCEPROP 2 LAST SIG_NAME IND_SOC_P0_CPL0
J 0
(-3785 3910);
DISPLAY 0.489362 (-3785 3910);
FORCEPROP 2 LASTPROP $XRERR UNIQUE?
J 0
(-4025 3910);
DISPLAY 0.638298 (-4025 3910);
PAINT MONO (-4025 3910);
DISPLAY INVISIBLE (-4025 3910);
WIRE 16 -1 (-4475 4150)(-3325 4150);
WIRE 16 -1 (-5425 4150)(-4475 4150);
FORCEPROP 2 LAST SIG_NAME SW_PVDDCR_SOC_P0_SW3
J 0
(-5310 4175);
DISPLAY 0.489362 (-5310 4175);
FORCEPROP 2 LASTPROP $XRERR UNIQUE?
J 0
(-5550 4175);
DISPLAY 0.638298 (-5550 4175);
PAINT MONO (-5550 4175);
DISPLAY INVISIBLE (-5550 4175);
WIRE 16 -1 (-4475 4150)(-4475 4075);
WIRE 16 -1 (-1825 4150)(-1825 3200);
WIRE 16 -1 (-1825 4150)(-1750 4150);
WIRE 16 -1 (-2525 4150)(-1825 4150);
WIRE 16 -1 (-1825 3200)(-3950 3200);
WIRE 16 -1 (-1750 4150)(-1325 4150);
WIRE 16 -1 (-1750 4150)(-1750 4075);
WIRE 16 -1 (-1325 4250)(-1325 4150);
WIRE 16 -1 (-1325 4150)(-1325 4075);
WIRE 16 -1 (-7650 3975)(-7650 4050);
WIRE 16 -1 (-6275 4050)(-7650 4050);
FORCEPROP 2 LAST SIG_NAME PVDDCR_CPU0_P0_VCCS
J 2
(-6335 4060);
DISPLAY 0.489362 (-6335 4060);
WIRE 16 -1 (-7825 4050)(-7650 4050);
WIRE 16 -1 (-3700 4275)(-3700 4250);
WIRE 16 -1 (-3700 4250)(-5425 4250);
FORCEPROP 2 LAST SIG_NAME SW_PVDDCR_SOC_P0_PH3
J 0
(-5310 4260);
DISPLAY 0.489362 (-5310 4260);
FORCEPROP 2 LASTPROP $XRERR UNIQUE?
J 0
(-5550 4260);
DISPLAY 0.638298 (-5550 4260);
PAINT MONO (-5550 4260);
DISPLAY INVISIBLE (-5550 4260);
WIRE 16 -1 (-4075 3850)(-4075 3900);
WIRE 16 -1 (-4075 3900)(-3975 3900);
WIRE 16 -1 (-6900 3850)(-6275 3850);
FORCEPROP 2 LAST SIG_NAME PVDDCR_SOC_P0_LSET3
J 2
(-6335 3860);
DISPLAY 0.489362 (-6335 3860);
FORCEPROP 2 LASTPROP $XRERR UNIQUE?
J 0
(-6575 3860);
DISPLAY 0.638298 (-6575 3860);
PAINT MONO (-6575 3860);
DISPLAY INVISIBLE (-6575 3860);
WIRE 16 -1 (-6275 3900)(-6725 3900);
FORCEPROP 2 LAST SIG_NAME NC_PVDDCR_SOC_P0_DNC3
J 2
(-6335 3910);
DISPLAY 0.489362 (-6335 3910);
FORCEPROP 2 LASTPROP $XRERR UNIQUE?
J 0
(-6965 3900);
DISPLAY 0.638298 (-6965 3900);
PAINT MONO (-6965 3900);
DISPLAY INVISIBLE (-6965 3900);
WIRE 16 -1 (-6275 3650)(-6900 3650);
FORCEPROP 2 LAST SIG_NAME PVDDCR_SOC_P0_TEMP1
J 2
(-6335 3660);
DISPLAY 0.489362 (-6335 3660);
WIRE 16 -1 (-6275 3550)(-6875 3550);
FORCEPROP 2 LAST SIG_NAME PVDDCR_SOC_P0_PWM3
J 2
(-6335 3560);
DISPLAY 0.489362 (-6335 3560);
WIRE 16 -1 (-5425 3550)(-5250 3550);
WIRE 16 -1 (-5250 3550)(-5250 3600);
WIRE 16 -1 (-5250 3475)(-5250 3550);
WIRE 16 -1 (-5250 3600)(-5250 3650);
WIRE 16 -1 (-5425 3600)(-5250 3600);
WIRE 16 -1 (-5425 3650)(-5250 3650);
WIRE 16 -1 (-5250 3700)(-5250 3650);
WIRE 16 -1 (-5250 3700)(-5425 3700);
WIRE 16 -1 (-5425 3850)(-4900 3850);
FORCEPROP 2 LAST SIG_NAME NC_PVDDCR_SOC_P0_GL1_3
J 0
(-5310 3860);
DISPLAY 0.489362 (-5310 3860);
FORCEPROP 2 LASTPROP $XRERR UNIQUE?
J 0
(-4870 3850);
DISPLAY 0.638298 (-4870 3850);
PAINT MONO (-4870 3850);
DISPLAY INVISIBLE (-4870 3850);
WIRE 16 -1 (-7325 4675)(-6850 4675);
WIRE 16 -1 (-7325 4875)(-7325 4675);
WIRE 16 -1 (-7325 4675)(-7325 4600);
WIRE 16 -1 (-6850 4675)(-6850 4500);
FORCEPROP 2 LAST SIG_NAME PVDDCR_SOC_P0_VCC3
J 2
(-6360 4510);
DISPLAY 0.489362 (-6360 4510);
FORCEPROP 2 LASTPROP $XRERR UNIQUE?
J 0
(-6600 4510);
DISPLAY 0.638298 (-6600 4510);
PAINT MONO (-6600 4510);
DISPLAY INVISIBLE (-6600 4510);
WIRE 16 -1 (-6850 4500)(-6275 4500);
WIRE 16 -1 (-6850 4500)(-6850 4300);
WIRE 16 -1 (-6850 4300)(-6275 4300);
WIRE 16 -1 (-7325 5075)(-7325 5200);
WIRE 16 -1 (-6975 5200)(-7325 5200);
WIRE 16 -1 (-7325 5325)(-7325 5200);
WIRE 16 -1 (-6625 5200)(-6975 5200);
WIRE 16 -1 (-6975 5075)(-6975 5200);
WIRE 16 -1 (-6625 4800)(-6625 5200);
WIRE 16 -1 (-6625 4800)(-6275 4800);
WIRE 16 -1 (-6275 4150)(-6925 4150);
FORCEPROP 2 LAST SIG_NAME PVDDCR_SOC_P0_IMON3
J 2
(-6335 4160);
DISPLAY 0.489362 (-6335 4160);
WIRE 16 -1 (-5325 4800)(-5325 4750);
WIRE 16 -1 (-5425 4800)(-5325 4800);
WIRE 16 -1 (-5325 5200)(-5325 4800);
WIRE 16 -1 (-5325 4750)(-5425 4750);
WIRE 16 -1 (-5325 5200)(-5025 5200);
WIRE 16 -1 (-5025 5200)(-4625 5200);
WIRE 16 -1 (-5025 5125)(-5025 5200);
WIRE 16 -1 (-4625 5200)(-4300 5200);
WIRE 16 -1 (-4625 5125)(-4625 5200);
WIRE 16 -1 (-4300 5200)(-3975 5200);
WIRE 16 -1 (-4300 5125)(-4300 5200);
WIRE 16 -1 (-3975 5200)(-3675 5200);
WIRE 16 -1 (-3975 5200)(-3975 5125);
WIRE 16 -1 (-3325 5200)(-3675 5200);
WIRE 16 -1 (-3675 5200)(-3675 5125);
WIRE 16 -1 (-3325 5275)(-3325 5200);
WIRE 16 -1 (-3325 5200)(-3325 5125);
WIRE 16 -1 (-5425 4500)(-4625 4500);
FORCEPROP 2 LAST SIG_NAME SW_PVDDCR_SOC_P0_BOOT3
J 0
(-5310 4510);
DISPLAY 0.489362 (-5310 4510);
FORCEPROP 2 LASTPROP $XRERR UNIQUE?
J 0
(-5550 4510);
DISPLAY 0.638298 (-5550 4510);
PAINT MONO (-5550 4510);
DISPLAY INVISIBLE (-5550 4510);
WIRE 16 -1 (-5025 4925)(-5025 4800);
WIRE 16 -1 (-5025 4800)(-4625 4800);
WIRE 16 -1 (-4625 4800)(-4300 4800);
WIRE 16 -1 (-4625 4925)(-4625 4800);
WIRE 16 -1 (-4300 4800)(-3975 4800);
WIRE 16 -1 (-4300 4925)(-4300 4800);
WIRE 16 -1 (-3675 4800)(-3975 4800);
WIRE 16 -1 (-3975 4925)(-3975 4800);
WIRE 16 -1 (-3325 4800)(-3675 4800);
WIRE 16 -1 (-3675 4925)(-3675 4800);
WIRE 16 -1 (-3325 4925)(-3325 4800);
WIRE 16 -1 (-3325 4800)(-3325 4750);
WIRE 16 -1 (-2525 3900)(-2100 3900);
FORCEPROP 2 LAST SIG_NAME IND_SOC_P0_CPL3
J 0
(-2435 3910);
DISPLAY 0.489362 (-2435 3910);
WIRE 16 -1 (-1750 3875)(-1750 3750);
WIRE 16 -1 (-1325 3750)(-1750 3750);
WIRE 16 -1 (-1325 3875)(-1325 3750);
WIRE 16 -1 (-1325 3675)(-1325 3750);
WIRE 16 -1 (-4425 4500)(-3700 4500);
FORCEPROP 2 LAST SIG_NAME SW_PVDDCR_SOC_P0_BOOT3_RC
J 2
(-3735 4510);
DISPLAY 0.489362 (-3735 4510);
FORCEPROP 2 LASTPROP $XRERR UNIQUE?
J 0
(-3975 4510);
DISPLAY 0.638298 (-3975 4510);
PAINT MONO (-3975 4510);
DISPLAY INVISIBLE (-3975 4510);
WIRE 16 -1 (-3700 4500)(-3700 4475);
DOT 1 (-3325 4800);
DOT 1 (-3675 4800);
DOT 1 (-3675 5200);
DOT 1 (-3325 5200);
DOT 1 (-5325 4800);
DOT 1 (-5250 3650);
DOT 1 (-7325 4675);
DOT 1 (-4300 4800);
DOT 1 (-6975 5200);
DOT 1 (-7325 5200);
DOT 1 (-1825 4150);
DOT 1 (-6850 4500);
DOT 1 (-1325 3750);
DOT 1 (-1750 4150);
DOT 1 (-1325 4150);
DOT 1 (-5250 3550);
DOT 1 (-5250 3600);
DOT 1 (-5025 5200);
DOT 1 (-4625 5200);
DOT 1 (-4300 5200);
DOT 1 (-3975 4800);
DOT 1 (-3975 5200);
DOT 1 (-7650 4050);
DOT 1 (-4625 4800);
DOT 1 (-4475 4150);
FORCENOTE
2ND=CV+22Y0EZ01
(-3875 3650) 0;
DISPLAY LEFT (-3875 3650);
DISPLAY 0.638298 (-3875 3650);
PAINT WHITE (-3875 3650);
FORCENOTE
HCME656510Q-221QL
(-3875 3850) 0;
DISPLAY LEFT (-3875 3850);
DISPLAY 0.638298 (-3875 3850);
PAINT WHITE (-3875 3850);
FORCENOTE
DCR=0.17M OHM
(-3875 3700) 0;
DISPLAY LEFT (-3875 3700);
DISPLAY 0.638298 (-3875 3700);
PAINT WHITE (-3875 3700);
FORCENOTE
6.5*6.5*10.0
(-3875 3750) 0;
DISPLAY LEFT (-3875 3750);
DISPLAY 0.638298 (-3875 3750);
PAINT WHITE (-3875 3750);
FORCENOTE
ISAT:30A@100C
(-3875 3800) 0;
DISPLAY LEFT (-3875 3800);
DISPLAY 0.638298 (-3875 3800);
PAINT WHITE (-3875 3800);
FORCENOTE
2ND=CV+15^0TZ01
(-2500 4225) 0;
DISPLAY LEFT (-2500 4225);
DISPLAY 0.638298 (-2500 4225);
PAINT WHITE (-2500 4225);
FORCENOTE
DCR=2-3,0.27M OHM
(-2500 4275) 0;
DISPLAY LEFT (-2500 4275);
DISPLAY 0.638298 (-2500 4275);
PAINT WHITE (-2500 4275);
FORCENOTE
DCR=1-4,0.105M OHM
(-2500 4325) 0;
DISPLAY LEFT (-2500 4325);
DISPLAY 0.638298 (-2500 4325);
PAINT WHITE (-2500 4325);
FORCENOTE
11.0*7.5*12.5
(-2500 4375) 0;
DISPLAY LEFT (-2500 4375);
DISPLAY 0.638298 (-2500 4375);
PAINT WHITE (-2500 4375);
FORCENOTE
ISAT:70A@100C
(-2500 4425) 0;
DISPLAY LEFT (-2500 4425);
DISPLAY 0.638298 (-2500 4425);
PAINT WHITE (-2500 4425);
FORCENOTE
PGL6303.151HLT
(-2500 4475) 0;
DISPLAY LEFT (-2500 4475);
DISPLAY 0.638298 (-2500 4475);
PAINT WHITE (-2500 4475);
FORCENOTE
PVDDCR_SOC_P0_PHASE3
(-6400 5550) 0;
DISPLAY LEFT (-6400 5550);
DISPLAY 1.595745 (-6400 5550);
PAINT WHITE (-6400 5550);
QUIT
